# SCM (Grand Teton) — schematic netlist excerpt (pin names and nets, part order shuffled) for the footprints in the layout excerpt that follows; sources: Cadence DE-HDL packaged netlist, KiCad conversion of 12092022_DA0F0TMDCD0_F0T_Management_Board_D_brd_V3_OCP.brd

PC253  Q_CAP  0.1UF 25V 10% X7R  pkg 0402  page 55 : A = SW_P1V2_AUX_FLT ; B = GND
C124  Q_CAP  22UF 6.3V 20% X6S  pkg C0603  page 16 : A = P1V8_AUX ; B = GND

(kicad_pcb
	(version 20260206)
	(generator "pcbnew")
	(generator_version "10.0")
	(general
		(thickness 1.6)
		(legacy_teardrops no)
	)
	(paper "A4")
	(title_block
		(title "12092022_DA0F0TMDCD0_F0T_Management_Board_D_brd_V3_OCP.brd")
		(comment 1 "Grand Teton / footprints 215-216 of 1440")
	)
	(layers
		(0 "F.Cu" signal "TOP")
		(4 "In1.Cu" signal "GND")
		(6 "In2.Cu" signal "IN1")
		(8 "In3.Cu" signal "GND1")
		(10 "In4.Cu" signal "IN2")
		(12 "In5.Cu" signal "VCC")
		(14 "In6.Cu" signal "VCC1")
		(16 "In7.Cu" signal "IN3")
		(18 "In8.Cu" signal "GND2")
		(20 "In9.Cu" signal "IN4")
		(22 "In10.Cu" signal "GND3")
		(2 "B.Cu" signal "BOTTOM")
		(9 "F.Adhes" user "F.Adhesive")
		(11 "B.Adhes" user "B.Adhesive")
		(13 "F.Paste" user "Package Geometry/Pastemask Top")
		(15 "B.Paste" user "Package Geometry/Pastemask Bottom")
		(5 "F.SilkS" user "Ref Des/Silkscreen Top")
		(7 "B.SilkS" user "Ref Des/Silkscreen Bottom")
		(1 "F.Mask" user "Board Geometry/Soldermask Top")
		(3 "B.Mask" user "Board Geometry/Soldermask Bottom")
		(17 "Dwgs.User" user "User.Drawings")
		(19 "Cmts.User" user "User.Comments")
		(21 "Eco1.User" user "User.Eco1")
		(23 "Eco2.User" user "User.Eco2")
		(25 "Edge.Cuts" user "Board Geometry/Outline")
		(27 "Margin" user)
		(31 "F.CrtYd" user "Package Geometry/Place Bound Top")
		(29 "B.CrtYd" user "Package Geometry/Place Bound Bottom")
		(35 "F.Fab" user "Ref Des/Assembly Top")
		(33 "B.Fab" user "Ref Des/Assembly Bottom")
	)
	(footprint ""
		(layer "F.Cu")
		(at 74.74712 -35.127438)
		(property "Reference" "C124"
			(at 0 0 0)
			(layer "F.SilkS")
			(hide yes)
			(effects
				(font
					(size 1.27 1.27)
				)
			)
		)
		(property "Value" ""
			(at 0 0 0)
			(layer "F.Fab")
			(effects
				(font
					(size 1.27 1.27)
				)
			)
		)
		(duplicate_pad_numbers_are_jumpers no)
		(fp_line
			(start -1.2954 -0.5842)
			(end 1.2954 -0.5842)
			(stroke
				(width 0.1524)
				(type default)
			)
			(layer "F.SilkS")
		)
		(fp_line
			(start -1.2954 0.5842)
			(end -1.2954 -0.5842)
			(stroke
				(width 0.1524)
				(type default)
			)
			(layer "F.SilkS")
		)
		(fp_line
			(start 0 -0.5842)
			(end 0 0.5842)
			(stroke
				(width 0.1524)
				(type default)
			)
			(layer "F.SilkS")
		)
		(fp_line
			(start 1.2954 -0.5842)
			(end 1.2954 0.5842)
			(stroke
				(width 0.1524)
				(type default)
			)
			(layer "F.SilkS")
		)
		(fp_line
			(start 1.2954 0.5842)
			(end -1.2954 0.5842)
			(stroke
				(width 0.1524)
				(type default)
			)
			(layer "F.SilkS")
		)
		(fp_line
			(start -1.1938 -0.4064)
			(end -0.8636 -0.4064)
			(stroke
				(width 0.1)
				(type default)
			)
			(layer "F.Fab")
		)
		(fp_line
			(start -1.1938 0.4064)
			(end -1.1938 -0.4064)
			(stroke
				(width 0.1)
				(type default)
			)
			(layer "F.Fab")
		)
		(fp_line
			(start -0.8636 -0.4572)
			(end 0.8636 -0.4572)
			(stroke
				(width 0.1)
				(type default)
			)
			(layer "F.Fab")
		)
		(fp_line
			(start -0.8636 -0.4064)
			(end -0.8636 -0.4572)
			(stroke
				(width 0.1)
				(type default)
			)
			(layer "F.Fab")
		)
		(fp_line
			(start -0.8636 0.4064)
			(end -1.1938 0.4064)
			(stroke
				(width 0.1)
				(type default)
			)
			(layer "F.Fab")
		)
		(fp_line
			(start -0.8636 0.4572)
			(end -0.8636 0.4064)
			(stroke
				(width 0.1)
				(type default)
			)
			(layer "F.Fab")
		)
		(fp_line
			(start 0.8636 -0.4572)
			(end 0.8636 -0.4064)
			(stroke
				(width 0.1)
				(type default)
			)
			(layer "F.Fab")
		)
		(fp_line
			(start 0.8636 -0.4064)
			(end 1.1938 -0.4064)
			(stroke
				(width 0.1)
				(type default)
			)
			(layer "F.Fab")
		)
		(fp_line
			(start 0.8636 0.4064)
			(end 0.8636 0.4572)
			(stroke
				(width 0.1)
				(type default)
			)
			(layer "F.Fab")
		)
		(fp_line
			(start 0.8636 0.4572)
			(end -0.8636 0.4572)
			(stroke
				(width 0.1)
				(type default)
			)
			(layer "F.Fab")
		)
		(fp_line
			(start 1.1938 -0.4064)
			(end 1.1938 0.4064)
			(stroke
				(width 0.1)
				(type default)
			)
			(layer "F.Fab")
		)
		(fp_line
			(start 1.1938 0.4064)
			(end 0.8636 0.4064)
			(stroke
				(width 0.1)
				(type default)
			)
			(layer "F.Fab")
		)
		(pad "1" smd rect
			(at -0.7366 0 270)
			(size 0.7112 0.8128)
			(layers "F.Cu" "F.Mask" "F.Paste")
			(net "P1V8_AUX")
		)
		(pad "2" smd rect
			(at 0.7366 0 270)
			(size 0.7112 0.8128)
			(layers "F.Cu" "F.Mask" "F.Paste")
			(net "GND")
		)
	)
	(footprint ""
		(layer "F.Cu")
		(at 81.701386 -74.883264 180)
		(property "Reference" "PC253"
			(at 0 0 180)
			(layer "F.SilkS")
			(hide yes)
			(effects
				(font
					(size 1.27 1.27)
				)
			)
		)
		(property "Value" ""
			(at 0 0 180)
			(layer "F.Fab")
			(effects
				(font
					(size 1.27 1.27)
				)
			)
		)
		(duplicate_pad_numbers_are_jumpers no)
		(fp_line
			(start 0.7874 0.4064)
			(end -0.7874 0.4064)
			(stroke
				(width 0.1524)
				(type default)
			)
			(layer "F.SilkS")
		)
		(fp_line
			(start 0.7874 -0.4064)
			(end 0.7874 0.4064)
			(stroke
				(width 0.1524)
				(type default)
			)
			(layer "F.SilkS")
		)
		(fp_line
			(start -0.7874 0.4064)
			(end -0.7874 -0.4064)
			(stroke
				(width 0.1524)
				(type default)
			)
			(layer "F.SilkS")
		)
		(fp_line
			(start -0.7874 -0.4064)
			(end 0.7874 -0.4064)
			(stroke
				(width 0.1524)
				(type default)
			)
			(layer "F.SilkS")
		)
		(fp_line
			(start 0.67945 0.3048)
			(end 0.120396 0.3048)
			(stroke
				(width 0.1)
				(type default)
			)
			(layer "F.Fab")
		)
		(fp_line
			(start 0.67945 -0.3048)
			(end 0.67945 0.3048)
			(stroke
				(width 0.1)
				(type default)
			)
			(layer "F.Fab")
		)
		(fp_line
			(start 0.12065 -0.2794)
			(end 0.12065 -0.3048)
			(stroke
				(width 0.1)
				(type default)
			)
			(layer "F.Fab")
		)
		(fp_line
			(start 0.12065 -0.3048)
			(end 0.67945 -0.3048)
			(stroke
				(width 0.1)
				(type default)
			)
			(layer "F.Fab")
		)
		(fp_line
			(start 0.120396 0.3048)
			(end 0.120396 0.2794)
			(stroke
				(width 0.1)
				(type default)
			)
			(layer "F.Fab")
		)
		(fp_line
			(start 0.120396 0.2794)
			(end -0.12065 0.2794)
			(stroke
				(width 0.1)
				(type default)
			)
			(layer "F.Fab")
		)
		(fp_line
			(start -0.12065 0.3048)
			(end -0.67945 0.3048)
			(stroke
				(width 0.1)
				(type default)
			)
			(layer "F.Fab")
		)
		(fp_line
			(start -0.12065 0.2794)
			(end -0.12065 0.3048)
			(stroke
				(width 0.1)
				(type default)
			)
			(layer "F.Fab")
		)
		(fp_line
			(start -0.12065 -0.2794)
			(end 0.12065 -0.2794)
			(stroke
				(width 0.1)
				(type default)
			)
			(layer "F.Fab")
		)
		(fp_line
			(start -0.12065 -0.305054)
			(end -0.12065 -0.2794)
			(stroke
				(width 0.1)
				(type default)
			)
			(layer "F.Fab")
		)
		(fp_line
			(start -0.67945 0.3048)
			(end -0.67945 -0.305054)
			(stroke
				(width 0.1)
				(type default)
			)
			(layer "F.Fab")
		)
		(fp_line
			(start -0.67945 -0.305054)
			(end -0.12065 -0.305054)
			(stroke
				(width 0.1)
				(type default)
			)
			(layer "F.Fab")
		)
		(pad "1" smd circle
			(at -0.40005 0 180)
			(size 0 0)
			(layers "F.Cu" "F.Mask" "F.Paste")
			(net "SW_P1V2_AUX_FLT")
		)
		(pad "2" smd circle
			(at 0.40005 0 180)
			(size 0 0)
			(layers "F.Cu" "F.Mask" "F.Paste")
			(net "GND")
		)
	)
)
